# BASEBOARD_FAB2 (Tioga Pass) — schematic netlist excerpt (pin names and nets, part order shuffled) for the footprints in the layout excerpt that follows; sources: Cadence DE-HDL packaged netlist, KiCad conversion of Wiwynn_Tioga_Pass_MB.brd

C9G14  CAP  47.0PF 50V 5% COG  pkg 0402LF  page 169 : A = A_P3V3_SCALED ; B = GND
R779  RES  0.0 5% CHIP  pkg 0402  page 244 : A = P3E_CPU0_PE1_PCH_RXP<11> ; B = P3E_CPU0_PE1_PCH_CON_RXP<11>
R760  RES  0.0 5% CHIP  pkg 0402  page 244 : A = P3E_CPU0_PE1_PCH_RXN<15> ; B = P3E_CPU0_PE1_PCH_CON_RXN<15>

(kicad_pcb
	(version 20260206)
	(generator "pcbnew")
	(generator_version "10.0")
	(general
		(thickness 1.6)
		(legacy_teardrops no)
	)
	(paper "A4")
	(title_block
		(title "Wiwynn_Tioga_Pass_MB.brd")
		(comment 1 "Tioga Pass / footprints 2525-2527 of 4770")
	)
	(layers
		(0 "F.Cu" signal "TOP")
		(4 "In1.Cu" signal "L2GND")
		(6 "In2.Cu" signal "L3")
		(8 "In3.Cu" signal "L4GND")
		(10 "In4.Cu" signal "L5")
		(12 "In5.Cu" signal "L6GND")
		(14 "In6.Cu" signal "L7VCC")
		(16 "In7.Cu" signal "L8VCC")
		(18 "In8.Cu" signal "L9GND")
		(20 "In9.Cu" signal "L10")
		(22 "In10.Cu" signal "L11GND")
		(24 "In11.Cu" signal "L12")
		(26 "In12.Cu" signal "L13GND")
		(2 "B.Cu" signal "BOTTOM")
		(9 "F.Adhes" user "F.Adhesive")
		(11 "B.Adhes" user "B.Adhesive")
		(13 "F.Paste" user "Package Geometry/Pastemask Top")
		(15 "B.Paste" user "Package Geometry/Pastemask Bottom")
		(5 "F.SilkS" user "Ref Des/Silkscreen Top")
		(7 "B.SilkS" user "Ref Des/Silkscreen Bottom")
		(1 "F.Mask" user "Board Geometry/Soldermask Top")
		(3 "B.Mask" user "Board Geometry/Soldermask Bottom")
		(17 "Dwgs.User" user "User.Drawings")
		(19 "Cmts.User" user "User.Comments")
		(21 "Eco1.User" user "User.Eco1")
		(23 "Eco2.User" user "User.Eco2")
		(25 "Edge.Cuts" user "Board Geometry/Outline")
		(27 "Margin" user)
		(31 "F.CrtYd" user "Package Geometry/Place Bound Top")
		(29 "B.CrtYd" user "Package Geometry/Place Bound Bottom")
		(35 "F.Fab" user "Ref Des/Assembly Top")
		(33 "B.Fab" user "Ref Des/Assembly Bottom")
	)
	(footprint ""
		(layer "B.Cu")
		(at 401.454874 -23.114)
		(property "Reference" "C9G14"
			(at 0 0 0)
			(layer "B.SilkS")
			(hide yes)
			(effects
				(font
					(size 1.27 1.27)
				)
				(justify mirror)
			)
		)
		(property "Value" ""
			(at 0 0 0)
			(layer "B.Fab")
			(effects
				(font
					(size 1.27 1.27)
				)
				(justify mirror)
			)
		)
		(duplicate_pad_numbers_are_jumpers no)
		(fp_poly
			(pts
				(xy -0.3048 -0.1016) (xy -0.3048 0.9906) (xy 0.3048 0.9906) (xy 0.3048 -0.1016)
			)
			(stroke
				(width 0)
				(type default)
			)
			(fill no)
			(layer "B.CrtYd")
		)
		(fp_line
			(start -0.3048 -0.1016)
			(end 0.3048 -0.1016)
			(stroke
				(width 0.1)
				(type default)
			)
			(layer "B.Fab")
		)
		(fp_line
			(start -0.3048 0.9906)
			(end -0.3048 -0.1016)
			(stroke
				(width 0.1)
				(type default)
			)
			(layer "B.Fab")
		)
		(fp_line
			(start 0.3048 -0.1016)
			(end 0.3048 0.9906)
			(stroke
				(width 0.1)
				(type default)
			)
			(layer "B.Fab")
		)
		(fp_line
			(start 0.3048 0.9906)
			(end -0.3048 0.9906)
			(stroke
				(width 0.1)
				(type default)
			)
			(layer "B.Fab")
		)
		(pad "1" smd rect
			(at 0 0 180)
			(size 0.508 0.508)
			(layers "B.Cu" "B.Mask" "B.Paste")
			(net "A_P3V3_SCALED")
		)
		(pad "2" smd rect
			(at 0 0.889 180)
			(size 0.508 0.508)
			(layers "B.Cu" "B.Mask" "B.Paste")
			(net "GND")
		)
		(zone
			(layer "B.Cu")
			(hatch none 0.5)
			(connect_pads
				(clearance 0)
			)
			(min_thickness 0.25)
			(keepout
				(tracks allowed)
				(vias not_allowed)
				(pads allowed)
				(copperpour not_allowed)
				(footprints allowed)
			)
			(placement
				(enabled no)
				(sheetname "")
			)
			(fill
				(thermal_gap 0.5)
				(thermal_bridge_width 0.5)
				(island_removal_mode 0)
			)
			(polygon
				(pts
					(xy 401.708874 -22.86) (xy 401.200874 -22.86) (xy 401.200874 -22.479) (xy 401.708874 -22.479)
				)
			)
		)
		(zone
			(layer "B.Cu")
			(hatch none 0.5)
			(connect_pads
				(clearance 0)
			)
			(min_thickness 0.25)
			(keepout
				(tracks not_allowed)
				(vias allowed)
				(pads allowed)
				(copperpour not_allowed)
				(footprints allowed)
			)
			(placement
				(enabled no)
				(sheetname "")
			)
			(fill
				(thermal_gap 0.5)
				(thermal_bridge_width 0.5)
				(island_removal_mode 0)
			)
			(polygon
				(pts
					(xy 401.708874 -22.479) (xy 401.200874 -22.479) (xy 401.200874 -22.86) (xy 401.708874 -22.86)
				)
			)
		)
	)
	(footprint ""
		(layer "B.Cu")
		(at 354.289614 -125.532642 -90)
		(property "Reference" "R760"
			(at 0.8382 -0.67818 270)
			(unlocked yes)
			(layer "B.SilkS")
			(effects
				(font
					(size 0.4064 0.254)
					(thickness 0.1524)
				)
				(justify left mirror)
			)
		)
		(property "Value" ""
			(at 0 0 90)
			(layer "B.Fab")
			(effects
				(font
					(size 1.27 1.27)
				)
				(justify mirror)
			)
		)
		(duplicate_pad_numbers_are_jumpers no)
		(fp_poly
			(pts
				(xy 0.2794 -0.1016) (xy -0.2794 -0.1016) (xy -0.2794 0.9906) (xy 0.2794 0.9906)
			)
			(stroke
				(width 0)
				(type default)
			)
			(fill no)
			(layer "B.CrtYd")
		)
		(fp_line
			(start -0.2794 0.9906)
			(end -0.2794 -0.1016)
			(stroke
				(width 0.1)
				(type default)
			)
			(layer "B.Fab")
		)
		(fp_line
			(start 0.2794 0.9906)
			(end -0.2794 0.9906)
			(stroke
				(width 0.1)
				(type default)
			)
			(layer "B.Fab")
		)
		(fp_line
			(start -0.2794 -0.1016)
			(end 0.2794 -0.1016)
			(stroke
				(width 0.1)
				(type default)
			)
			(layer "B.Fab")
		)
		(fp_line
			(start 0.2794 -0.1016)
			(end 0.2794 0.9906)
			(stroke
				(width 0.1)
				(type default)
			)
			(layer "B.Fab")
		)
		(pad "1" smd rect
			(at 0 0 90)
			(size 0.508 0.508)
			(layers "B.Cu" "B.Mask" "B.Paste")
			(net "P3E_CPU0_PE1_PCH_RXN<15>")
		)
		(pad "2" smd rect
			(at 0 0.889 90)
			(size 0.508 0.508)
			(layers "B.Cu" "B.Mask" "B.Paste")
			(net "P3E_CPU0_PE1_PCH_CON_RXN<15>")
		)
		(zone
			(layer "B.Cu")
			(hatch none 0.5)
			(connect_pads
				(clearance 0)
			)
			(min_thickness 0.25)
			(keepout
				(tracks not_allowed)
				(vias allowed)
				(pads allowed)
				(copperpour not_allowed)
				(footprints allowed)
			)
			(placement
				(enabled no)
				(sheetname "")
			)
			(fill
				(thermal_gap 0.5)
				(thermal_bridge_width 0.5)
				(island_removal_mode 0)
			)
			(polygon
				(pts
					(xy 353.654614 -125.278642) (xy 353.654614 -125.786642) (xy 354.035614 -125.786642) (xy 354.035614 -125.278642)
				)
			)
		)
		(zone
			(layer "B.Cu")
			(hatch none 0.5)
			(connect_pads
				(clearance 0)
			)
			(min_thickness 0.25)
			(keepout
				(tracks allowed)
				(vias not_allowed)
				(pads allowed)
				(copperpour not_allowed)
				(footprints allowed)
			)
			(placement
				(enabled no)
				(sheetname "")
			)
			(fill
				(thermal_gap 0.5)
				(thermal_bridge_width 0.5)
				(island_removal_mode 0)
			)
			(polygon
				(pts
					(xy 354.035614 -125.278642) (xy 354.035614 -125.786642) (xy 353.654614 -125.786642) (xy 353.654614 -125.278642)
				)
			)
		)
	)
	(footprint ""
		(layer "B.Cu")
		(at 361.826556 -121.392442 -90)
		(property "Reference" "R779"
			(at 0.8382 -0.67818 270)
			(unlocked yes)
			(layer "B.SilkS")
			(effects
				(font
					(size 0.4064 0.254)
					(thickness 0.1524)
				)
				(justify left mirror)
			)
		)
		(property "Value" ""
			(at 0 0 90)
			(layer "B.Fab")
			(effects
				(font
					(size 1.27 1.27)
				)
				(justify mirror)
			)
		)
		(duplicate_pad_numbers_are_jumpers no)
		(fp_poly
			(pts
				(xy 0.2794 -0.1016) (xy -0.2794 -0.1016) (xy -0.2794 0.9906) (xy 0.2794 0.9906)
			)
			(stroke
				(width 0)
				(type default)
			)
			(fill no)
			(layer "B.CrtYd")
		)
		(fp_line
			(start -0.2794 0.9906)
			(end -0.2794 -0.1016)
			(stroke
				(width 0.1)
				(type default)
			)
			(layer "B.Fab")
		)
		(fp_line
			(start 0.2794 0.9906)
			(end -0.2794 0.9906)
			(stroke
				(width 0.1)
				(type default)
			)
			(layer "B.Fab")
		)
		(fp_line
			(start -0.2794 -0.1016)
			(end 0.2794 -0.1016)
			(stroke
				(width 0.1)
				(type default)
			)
			(layer "B.Fab")
		)
		(fp_line
			(start 0.2794 -0.1016)
			(end 0.2794 0.9906)
			(stroke
				(width 0.1)
				(type default)
			)
			(layer "B.Fab")
		)
		(pad "1" smd rect
			(at 0 0 90)
			(size 0.508 0.508)
			(layers "B.Cu" "B.Mask" "B.Paste")
			(net "P3E_CPU0_PE1_PCH_RXP<11>")
		)
		(pad "2" smd rect
			(at 0 0.889 90)
			(size 0.508 0.508)
			(layers "B.Cu" "B.Mask" "B.Paste")
			(net "P3E_CPU0_PE1_PCH_CON_RXP<11>")
		)
		(zone
			(layer "B.Cu")
			(hatch none 0.5)
			(connect_pads
				(clearance 0)
			)
			(min_thickness 0.25)
			(keepout
				(tracks not_allowed)
				(vias allowed)
				(pads allowed)
				(copperpour not_allowed)
				(footprints allowed)
			)
			(placement
				(enabled no)
				(sheetname "")
			)
			(fill
				(thermal_gap 0.5)
				(thermal_bridge_width 0.5)
				(island_removal_mode 0)
			)
			(polygon
				(pts
					(xy 361.191556 -121.138442) (xy 361.191556 -121.646442) (xy 361.572556 -121.646442) (xy 361.572556 -121.138442)
				)
			)
		)
		(zone
			(layer "B.Cu")
			(hatch none 0.5)
			(connect_pads
				(clearance 0)
			)
			(min_thickness 0.25)
			(keepout
				(tracks allowed)
				(vias not_allowed)
				(pads allowed)
				(copperpour not_allowed)
				(footprints allowed)
			)
			(placement
				(enabled no)
				(sheetname "")
			)
			(fill
				(thermal_gap 0.5)
				(thermal_bridge_width 0.5)
				(island_removal_mode 0)
			)
			(polygon
				(pts
					(xy 361.572556 -121.138442) (xy 361.572556 -121.646442) (xy 361.191556 -121.646442) (xy 361.191556 -121.138442)
				)
			)
		)
	)
)
